(kicad_pcb
	(version 20260206)
	(generator "pcbnew")
	(generator_version "10.0")
	(general
		(thickness 1.6)
		(legacy_teardrops no)
	)
	(paper "A4")
	(title_block
		(title "Bryce Canyon_R.DPB_16317-1_OCP.brd")
		(comment 1 "Bryce Canyon / footprints 1440-1447 of 2099")
	)
	(layers
		(0 "F.Cu" signal "TOP")
		(4 "In1.Cu" signal "L2GND")
		(6 "In2.Cu" signal "L3")
		(8 "In3.Cu" signal "L4VCC")
		(10 "In4.Cu" signal "L5VCC")
		(12 "In5.Cu" signal "L6")
		(14 "In6.Cu" signal "L7GND")
		(2 "B.Cu" signal "BOTTOM")
		(9 "F.Adhes" user "F.Adhesive")
		(11 "B.Adhes" user "B.Adhesive")
		(13 "F.Paste" user "Package Geometry/Pastemask Top")
		(15 "B.Paste" user "Package Geometry/Pastemask Bottom")
		(5 "F.SilkS" user "Ref Des/Silkscreen Top")
		(7 "B.SilkS" user "Ref Des/Silkscreen Bottom")
		(1 "F.Mask" user "Board Geometry/Soldermask Top")
		(3 "B.Mask" user "Board Geometry/Soldermask Bottom")
		(17 "Dwgs.User" user "User.Drawings")
		(19 "Cmts.User" user "User.Comments")
		(21 "Eco1.User" user "User.Eco1")
		(23 "Eco2.User" user "User.Eco2")
		(25 "Edge.Cuts" user "Board Geometry/Outline")
		(27 "Margin" user)
		(31 "F.CrtYd" user "Package Geometry/Place Bound Top")
		(29 "B.CrtYd" user "Package Geometry/Place Bound Bottom")
		(35 "F.Fab" user "Ref Des/Assembly Top")
		(33 "B.Fab" user "Ref Des/Assembly Bottom")
	)
	(footprint ""
		(layer "F.Cu")
		(at 470.662 -244.348 180)
		(property "Reference" "R340"
			(at 0 0 180)
			(layer "F.SilkS")
			(hide yes)
			(effects
				(font
					(size 1.27 1.27)
				)
			)
		)
		(property "Value" "1KR2F-3-GP"
			(at 0.064008 -3.993896 180)
			(unlocked yes)
			(layer "F.Fab")
			(hide yes)
			(effects
				(font
					(size 1.016 1.016)
					(thickness 0.1524)
				)
			)
		)
		(property "Device Type" "R402H16"
			(at 0.064008 -5.517896 180)
			(unlocked yes)
			(layer "F.Fab")
			(hide yes)
			(effects
				(font
					(size 1.016 1.016)
					(thickness 0.1524)
				)
			)
		)
		(duplicate_pad_numbers_are_jumpers no)
		(fp_line
			(start 0.508 -0.9398)
			(end -0.508 -0.9398)
			(stroke
				(width 0.1524)
				(type default)
			)
			(layer "F.SilkS")
		)
		(fp_line
			(start -0.508 -0.9398)
			(end -0.508 0.9398)
			(stroke
				(width 0.1524)
				(type default)
			)
			(layer "F.SilkS")
		)
		(fp_rect
			(start -0.508 0.9398)
			(end 0.508 -0.9398)
			(stroke
				(width 0)
				(type default)
			)
			(fill no)
			(layer "F.CrtYd")
		)
		(fp_rect
			(start -0.508 0.9398)
			(end 0.508 -0.9398)
			(stroke
				(width 0)
				(type default)
			)
			(fill no)
			(layer "F.Fab")
		)
		(pad "1" smd custom
			(at 0 -0.4445 180)
			(size 0.1397 0.1397)
			(layers "F.Cu" "F.Mask" "F.Paste")
			(net "P3V3_STBY_B")
			(options
				(clearance outline)
				(anchor circle)
			)
			(primitives
				(gr_poly
					(pts
						(arc
							(start -0.1778 -0.2794)
							(mid -0.249642 -0.249642)
							(end -0.2794 -0.1778)
						)
						(arc
							(start -0.2794 0.1778)
							(mid -0.249642 0.249642)
							(end -0.1778 0.2794)
						)
						(arc
							(start 0.1778 0.2794)
							(mid 0.249642 0.249642)
							(end 0.2794 0.1778)
						)
						(arc
							(start 0.2794 -0.1778)
							(mid 0.249642 -0.249642)
							(end 0.1778 -0.2794)
						)
					)
					(width 0)
					(fill yes)
				)
			)
		)
		(pad "2" smd custom
			(at 0 0.4445 180)
			(size 0.1397 0.1397)
			(layers "F.Cu" "F.Mask" "F.Paste")
			(net "SW_PWR_R_HDD11")
			(options
				(clearance outline)
				(anchor circle)
			)
			(primitives
				(gr_poly
					(pts
						(arc
							(start -0.1778 -0.2794)
							(mid -0.249642 -0.249642)
							(end -0.2794 -0.1778)
						)
						(arc
							(start -0.2794 0.1778)
							(mid -0.249642 0.249642)
							(end -0.1778 0.2794)
						)
						(arc
							(start 0.1778 0.2794)
							(mid 0.249642 0.249642)
							(end 0.2794 0.1778)
						)
						(arc
							(start 0.2794 -0.1778)
							(mid 0.249642 -0.249642)
							(end 0.1778 -0.2794)
						)
					)
					(width 0)
					(fill yes)
				)
			)
		)
	)
	(footprint ""
		(layer "F.Cu")
		(at 252.544834 -372.342918)
		(property "Reference" "R1036"
			(at 0 0 0)
			(layer "F.SilkS")
			(hide yes)
			(effects
				(font
					(size 1.27 1.27)
				)
			)
		)
		(property "Value" "100KR2F-L1-GP"
			(at 0.064008 -3.993896 0)
			(unlocked yes)
			(layer "F.Fab")
			(hide yes)
			(effects
				(font
					(size 1.016 1.016)
					(thickness 0.1524)
				)
			)
		)
		(property "Device Type" "R402H16"
			(at 0.064008 -5.517896 0)
			(unlocked yes)
			(layer "F.Fab")
			(hide yes)
			(effects
				(font
					(size 1.016 1.016)
					(thickness 0.1524)
				)
			)
		)
		(duplicate_pad_numbers_are_jumpers no)
		(fp_line
			(start -0.508 -0.9398)
			(end -0.508 0.9398)
			(stroke
				(width 0.1524)
				(type default)
			)
			(layer "F.SilkS")
		)
		(fp_line
			(start 0.508 -0.9398)
			(end -0.508 -0.9398)
			(stroke
				(width 0.1524)
				(type default)
			)
			(layer "F.SilkS")
		)
		(fp_rect
			(start -0.508 0.9398)
			(end 0.508 -0.9398)
			(stroke
				(width 0)
				(type default)
			)
			(fill no)
			(layer "F.CrtYd")
		)
		(fp_rect
			(start -0.508 0.9398)
			(end 0.508 -0.9398)
			(stroke
				(width 0)
				(type default)
			)
			(fill no)
			(layer "F.Fab")
		)
		(pad "1" smd custom
			(at 0 -0.4445)
			(size 0.1397 0.1397)
			(layers "F.Cu" "F.Mask" "F.Paste")
			(net "P12V_B")
			(options
				(clearance outline)
				(anchor circle)
			)
			(primitives
				(gr_poly
					(pts
						(arc
							(start -0.1778 -0.2794)
							(mid -0.249642 -0.249642)
							(end -0.2794 -0.1778)
						)
						(arc
							(start -0.2794 0.1778)
							(mid -0.249642 0.249642)
							(end -0.1778 0.2794)
						)
						(arc
							(start 0.1778 0.2794)
							(mid 0.249642 0.249642)
							(end 0.2794 0.1778)
						)
						(arc
							(start 0.2794 -0.1778)
							(mid 0.249642 -0.249642)
							(end 0.1778 -0.2794)
						)
					)
					(width 0)
					(fill yes)
				)
			)
		)
		(pad "2" smd custom
			(at 0 0.4445)
			(size 0.1397 0.1397)
			(layers "F.Cu" "F.Mask" "F.Paste")
			(net "MB3_P12V_PWGIN_R")
			(options
				(clearance outline)
				(anchor circle)
			)
			(primitives
				(gr_poly
					(pts
						(arc
							(start -0.1778 -0.2794)
							(mid -0.249642 -0.249642)
							(end -0.2794 -0.1778)
						)
						(arc
							(start -0.2794 0.1778)
							(mid -0.249642 0.249642)
							(end -0.1778 0.2794)
						)
						(arc
							(start 0.1778 0.2794)
							(mid 0.249642 0.249642)
							(end 0.2794 0.1778)
						)
						(arc
							(start 0.2794 -0.1778)
							(mid 0.249642 -0.249642)
							(end 0.1778 -0.2794)
						)
					)
					(width 0)
					(fill yes)
				)
			)
		)
	)
	(footprint ""
		(layer "F.Cu")
		(at 43.40606 -119.783606 -90)
		(property "Reference" "R1131"
			(at 0 0 270)
			(layer "F.SilkS")
			(hide yes)
			(effects
				(font
					(size 1.27 1.27)
				)
			)
		)
		(property "Value" "143KR2F-L-1-GP"
			(at 0.064008 -3.993896 270)
			(unlocked yes)
			(layer "F.Fab")
			(hide yes)
			(effects
				(font
					(size 1.016 1.016)
					(thickness 0.1524)
				)
			)
		)
		(property "Device Type" "R402H16"
			(at 0.064008 -5.517896 270)
			(unlocked yes)
			(layer "F.Fab")
			(hide yes)
			(effects
				(font
					(size 1.016 1.016)
					(thickness 0.1524)
				)
			)
		)
		(duplicate_pad_numbers_are_jumpers no)
		(fp_line
			(start -0.508 -0.9398)
			(end -0.508 0.9398)
			(stroke
				(width 0.1524)
				(type default)
			)
			(layer "F.SilkS")
		)
		(fp_line
			(start 0.508 -0.9398)
			(end -0.508 -0.9398)
			(stroke
				(width 0.1524)
				(type default)
			)
			(layer "F.SilkS")
		)
		(fp_rect
			(start -0.508 0.9398)
			(end 0.508 -0.9398)
			(stroke
				(width 0)
				(type default)
			)
			(fill no)
			(layer "F.CrtYd")
		)
		(fp_rect
			(start -0.508 0.9398)
			(end 0.508 -0.9398)
			(stroke
				(width 0)
				(type default)
			)
			(fill no)
			(layer "F.Fab")
		)
		(pad "1" smd custom
			(at 0 -0.4445 270)
			(size 0.1397 0.1397)
			(layers "F.Cu" "F.Mask" "F.Paste")
			(net "AGND_P5V_B_2")
			(options
				(clearance outline)
				(anchor circle)
			)
			(primitives
				(gr_poly
					(pts
						(arc
							(start -0.1778 -0.2794)
							(mid -0.249642 -0.249642)
							(end -0.2794 -0.1778)
						)
						(arc
							(start -0.2794 0.1778)
							(mid -0.249642 0.249642)
							(end -0.1778 0.2794)
						)
						(arc
							(start 0.1778 0.2794)
							(mid 0.249642 0.249642)
							(end 0.2794 0.1778)
						)
						(arc
							(start 0.2794 -0.1778)
							(mid 0.249642 -0.249642)
							(end 0.1778 -0.2794)
						)
					)
					(width 0)
					(fill yes)
				)
			)
		)
		(pad "2" smd custom
			(at 0 0.4445 270)
			(size 0.1397 0.1397)
			(layers "F.Cu" "F.Mask" "F.Paste")
			(net "P5V_B_2_TRIP")
			(options
				(clearance outline)
				(anchor circle)
			)
			(primitives
				(gr_poly
					(pts
						(arc
							(start -0.1778 -0.2794)
							(mid -0.249642 -0.249642)
							(end -0.2794 -0.1778)
						)
						(arc
							(start -0.2794 0.1778)
							(mid -0.249642 0.249642)
							(end -0.1778 0.2794)
						)
						(arc
							(start 0.1778 0.2794)
							(mid 0.249642 0.249642)
							(end 0.2794 0.1778)
						)
						(arc
							(start 0.2794 -0.1778)
							(mid 0.249642 -0.249642)
							(end 0.1778 -0.2794)
						)
					)
					(width 0)
					(fill yes)
				)
			)
		)
	)
	(footprint ""
		(layer "F.Cu")
		(at 394.589 -147.066 -90)
		(property "Reference" "R529"
			(at 0 0 270)
			(layer "F.SilkS")
			(hide yes)
			(effects
				(font
					(size 1.27 1.27)
				)
			)
		)
		(property "Value" "2R6F-GP"
			(at -0.0508 -4.8514 270)
			(unlocked yes)
			(layer "F.Fab")
			(hide yes)
			(effects
				(font
					(size 1.016 1.016)
					(thickness 0.1524)
				)
			)
		)
		(property "Device Type" "R1206H26"
			(at 0 -6.3754 270)
			(unlocked yes)
			(layer "F.Fab")
			(hide yes)
			(effects
				(font
					(size 1.016 1.016)
					(thickness 0.1524)
				)
			)
		)
		(duplicate_pad_numbers_are_jumpers no)
		(fp_line
			(start -1.016 2.2352)
			(end -1.016 -2.2352)
			(stroke
				(width 0.1524)
				(type default)
			)
			(layer "F.SilkS")
		)
		(fp_line
			(start 1.016 2.2352)
			(end -1.016 2.2352)
			(stroke
				(width 0.1524)
				(type default)
			)
			(layer "F.SilkS")
		)
		(fp_line
			(start -1.016 -2.2352)
			(end 1.016 -2.2352)
			(stroke
				(width 0.1524)
				(type default)
			)
			(layer "F.SilkS")
		)
		(fp_line
			(start 1.016 -2.2352)
			(end 1.016 2.2352)
			(stroke
				(width 0.1524)
				(type default)
			)
			(layer "F.SilkS")
		)
		(fp_rect
			(start -1.0922 2.3114)
			(end 1.0922 -2.3114)
			(stroke
				(width 0)
				(type default)
			)
			(fill no)
			(layer "F.CrtYd")
		)
		(fp_poly
			(pts
				(xy -1.0922 -2.3114) (xy 1.0922 -2.3114) (xy 1.0922 2.3114) (xy -1.0922 2.3114)
			)
			(stroke
				(width 0)
				(type default)
			)
			(fill no)
			(layer "F.Fab")
		)
		(pad "1" smd rect
			(at 0 -1.397 270)
			(size 1.651 1.27)
			(layers "F.Cu" "F.Mask" "F.Paste")
			(net "P5V_HDD20")
		)
		(pad "2" smd rect
			(at 0 1.397 270)
			(size 1.651 1.27)
			(layers "F.Cu" "F.Mask" "F.Paste")
			(net "5V_PRE_20")
		)
	)
	(footprint ""
		(layer "F.Cu")
		(at 466.5218 -7.4422 -90)
		(property "Reference" "R136"
			(at 0 0 270)
			(layer "F.SilkS")
			(hide yes)
			(effects
				(font
					(size 1.27 1.27)
				)
			)
		)
		(property "Value" "4K7R2F-GP"
			(at 0.064008 -3.993896 270)
			(unlocked yes)
			(layer "F.Fab")
			(hide yes)
			(effects
				(font
					(size 1.016 1.016)
					(thickness 0.1524)
				)
			)
		)
		(property "Device Type" "R402H16"
			(at 0.064008 -5.517896 270)
			(unlocked yes)
			(layer "F.Fab")
			(hide yes)
			(effects
				(font
					(size 1.016 1.016)
					(thickness 0.1524)
				)
			)
		)
		(duplicate_pad_numbers_are_jumpers no)
		(fp_line
			(start -0.508 -0.9398)
			(end -0.508 0.9398)
			(stroke
				(width 0.1524)
				(type default)
			)
			(layer "F.SilkS")
		)
		(fp_line
			(start 0.508 -0.9398)
			(end -0.508 -0.9398)
			(stroke
				(width 0.1524)
				(type default)
			)
			(layer "F.SilkS")
		)
		(fp_rect
			(start -0.508 0.9398)
			(end 0.508 -0.9398)
			(stroke
				(width 0)
				(type default)
			)
			(fill no)
			(layer "F.CrtYd")
		)
		(fp_rect
			(start -0.508 0.9398)
			(end 0.508 -0.9398)
			(stroke
				(width 0)
				(type default)
			)
			(fill no)
			(layer "F.Fab")
		)
		(pad "1" smd custom
			(at 0 -0.4445 270)
			(size 0.1397 0.1397)
			(layers "F.Cu" "F.Mask" "F.Paste")
			(net "P3V3_STBY_B")
			(options
				(clearance outline)
				(anchor circle)
			)
			(primitives
				(gr_poly
					(pts
						(arc
							(start -0.1778 -0.2794)
							(mid -0.249642 -0.249642)
							(end -0.2794 -0.1778)
						)
						(arc
							(start -0.2794 0.1778)
							(mid -0.249642 0.249642)
							(end -0.1778 0.2794)
						)
						(arc
							(start 0.1778 0.2794)
							(mid 0.249642 0.249642)
							(end 0.2794 0.1778)
						)
						(arc
							(start 0.2794 -0.1778)
							(mid 0.249642 -0.249642)
							(end 0.1778 -0.2794)
						)
					)
					(width 0)
					(fill yes)
				)
			)
		)
		(pad "2" smd custom
			(at 0 0.4445 270)
			(size 0.1397 0.1397)
			(layers "F.Cu" "F.Mask" "F.Paste")
			(net "TEMP2_A0")
			(options
				(clearance outline)
				(anchor circle)
			)
			(primitives
				(gr_poly
					(pts
						(arc
							(start -0.1778 -0.2794)
							(mid -0.249642 -0.249642)
							(end -0.2794 -0.1778)
						)
						(arc
							(start -0.2794 0.1778)
							(mid -0.249642 0.249642)
							(end -0.1778 0.2794)
						)
						(arc
							(start 0.1778 0.2794)
							(mid 0.249642 0.249642)
							(end 0.2794 0.1778)
						)
						(arc
							(start 0.2794 -0.1778)
							(mid 0.249642 -0.249642)
							(end 0.1778 -0.2794)
						)
					)
					(width 0)
					(fill yes)
				)
			)
		)
	)
	(footprint ""
		(layer "F.Cu")
		(at 363.1184 -249.5296 90)
		(property "Reference" "R275"
			(at 0 0 90)
			(layer "F.SilkS")
			(hide yes)
			(effects
				(font
					(size 1.27 1.27)
				)
			)
		)
		(property "Value" "4K7R2J-2-GP"
			(at 0.064008 -3.993896 90)
			(unlocked yes)
			(layer "F.Fab")
			(hide yes)
			(effects
				(font
					(size 1.016 1.016)
					(thickness 0.1524)
				)
			)
		)
		(property "Device Type" "R402H16"
			(at 0.064008 -5.517896 90)
			(unlocked yes)
			(layer "F.Fab")
			(hide yes)
			(effects
				(font
					(size 1.016 1.016)
					(thickness 0.1524)
				)
			)
		)
		(duplicate_pad_numbers_are_jumpers no)
		(fp_line
			(start 0.508 -0.9398)
			(end -0.508 -0.9398)
			(stroke
				(width 0.1524)
				(type default)
			)
			(layer "F.SilkS")
		)
		(fp_line
			(start -0.508 -0.9398)
			(end -0.508 0.9398)
			(stroke
				(width 0.1524)
				(type default)
			)
			(layer "F.SilkS")
		)
		(fp_rect
			(start -0.508 0.9398)
			(end 0.508 -0.9398)
			(stroke
				(width 0)
				(type default)
			)
			(fill no)
			(layer "F.CrtYd")
		)
		(fp_rect
			(start -0.508 0.9398)
			(end 0.508 -0.9398)
			(stroke
				(width 0)
				(type default)
			)
			(fill no)
			(layer "F.Fab")
		)
		(pad "1" smd custom
			(at 0 -0.4445 90)
			(size 0.1397 0.1397)
			(layers "F.Cu" "F.Mask" "F.Paste")
			(net "P12V_B")
			(options
				(clearance outline)
				(anchor circle)
			)
			(primitives
				(gr_poly
					(pts
						(arc
							(start -0.1778 -0.2794)
							(mid -0.249642 -0.249642)
							(end -0.2794 -0.1778)
						)
						(arc
							(start -0.2794 0.1778)
							(mid -0.249642 0.249642)
							(end -0.1778 0.2794)
						)
						(arc
							(start 0.1778 0.2794)
							(mid 0.249642 0.249642)
							(end 0.2794 0.1778)
						)
						(arc
							(start 0.2794 -0.1778)
							(mid 0.249642 -0.249642)
							(end 0.1778 -0.2794)
						)
					)
					(width 0)
					(fill yes)
				)
			)
		)
		(pad "2" smd custom
			(at 0 0.4445 90)
			(size 0.1397 0.1397)
			(layers "F.Cu" "F.Mask" "F.Paste")
			(net "SW_HDD_P7")
			(options
				(clearance outline)
				(anchor circle)
			)
			(primitives
				(gr_poly
					(pts
						(arc
							(start -0.1778 -0.2794)
							(mid -0.249642 -0.249642)
							(end -0.2794 -0.1778)
						)
						(arc
							(start -0.2794 0.1778)
							(mid -0.249642 0.249642)
							(end -0.1778 0.2794)
						)
						(arc
							(start 0.1778 0.2794)
							(mid 0.249642 0.249642)
							(end 0.2794 0.1778)
						)
						(arc
							(start 0.2794 -0.1778)
							(mid 0.249642 -0.249642)
							(end 0.1778 -0.2794)
						)
					)
					(width 0)
					(fill yes)
				)
			)
		)
	)
	(footprint ""
		(layer "F.Cu")
		(at 426.085 -32.004 -90)
		(property "Reference" "R828"
			(at 0 0 270)
			(layer "F.SilkS")
			(hide yes)
			(effects
				(font
					(size 1.27 1.27)
				)
			)
		)
		(property "Value" "2R6F-GP"
			(at -0.0508 -4.8514 270)
			(unlocked yes)
			(layer "F.Fab")
			(hide yes)
			(effects
				(font
					(size 1.016 1.016)
					(thickness 0.1524)
				)
			)
		)
		(property "Device Type" "R1206H26"
			(at 0 -6.3754 270)
			(unlocked yes)
			(layer "F.Fab")
			(hide yes)
			(effects
				(font
					(size 1.016 1.016)
					(thickness 0.1524)
				)
			)
		)
		(duplicate_pad_numbers_are_jumpers no)
		(fp_line
			(start -1.016 2.2352)
			(end -1.016 -2.2352)
			(stroke
				(width 0.1524)
				(type default)
			)
			(layer "F.SilkS")
		)
		(fp_line
			(start 1.016 2.2352)
			(end -1.016 2.2352)
			(stroke
				(width 0.1524)
				(type default)
			)
			(layer "F.SilkS")
		)
		(fp_line
			(start -1.016 -2.2352)
			(end 1.016 -2.2352)
			(stroke
				(width 0.1524)
				(type default)
			)
			(layer "F.SilkS")
		)
		(fp_line
			(start 1.016 -2.2352)
			(end 1.016 2.2352)
			(stroke
				(width 0.1524)
				(type default)
			)
			(layer "F.SilkS")
		)
		(fp_rect
			(start -1.0922 2.3114)
			(end 1.0922 -2.3114)
			(stroke
				(width 0)
				(type default)
			)
			(fill no)
			(layer "F.CrtYd")
		)
		(fp_poly
			(pts
				(xy -1.0922 -2.3114) (xy 1.0922 -2.3114) (xy 1.0922 2.3114) (xy -1.0922 2.3114)
			)
			(stroke
				(width 0)
				(type default)
			)
			(fill no)
			(layer "F.Fab")
		)
		(pad "1" smd rect
			(at 0 -1.397 270)
			(size 1.651 1.27)
			(layers "F.Cu" "F.Mask" "F.Paste")
			(net "P5V_HDD33")
		)
		(pad "2" smd rect
			(at 0 1.397 270)
			(size 1.651 1.27)
			(layers "F.Cu" "F.Mask" "F.Paste")
			(net "5V_PRE_33")
		)
	)
	(footprint ""
		(layer "F.Cu")
		(at 158.663386 -245.219474 90)
		(property "Reference" "C81"
			(at 0 0 90)
			(layer "F.SilkS")
			(hide yes)
			(effects
				(font
					(size 1.27 1.27)
				)
			)
		)
		(property "Value" "SCD01U16V1KX-GP"
			(at -2.8321 -1.7399 90)
			(unlocked yes)
			(layer "F.Fab")
			(hide yes)
			(effects
				(font
					(size 1.016 1.016)
					(thickness 0.1524)
				)
			)
		)
		(property "Device Type" "C0201H13"
			(at -2.8321 -3.2639 90)
			(unlocked yes)
			(layer "F.Fab")
			(hide yes)
			(effects
				(font
					(size 1.016 1.016)
					(thickness 0.1524)
				)
			)
		)
		(duplicate_pad_numbers_are_jumpers no)
		(fp_rect
			(start -0.2794 0.6477)
			(end 0.2794 -0.6477)
			(stroke
				(width 0)
				(type default)
			)
			(fill no)
			(layer "F.CrtYd")
		)
		(fp_rect
			(start -0.2794 0.6477)
			(end 0.2794 -0.6477)
			(stroke
				(width 0)
				(type default)
			)
			(fill no)
			(layer "F.Fab")
		)
		(pad "1" smd custom
			(at 0 -0.2794 90)
			(size 0.0762 0.0762)
			(layers "F.Cu" "F.Mask" "F.Paste")
			(net "SAS_HDD_RX_N4")
			(options
				(clearance outline)
				(anchor circle)
			)
			(primitives
				(gr_poly
					(pts
						(arc
							(start 0.1524 -0.127)
							(mid 0.137521 -0.162921)
							(end 0.1016 -0.1778)
						)
						(arc
							(start -0.1016 -0.1778)
							(mid -0.137521 -0.162921)
							(end -0.1524 -0.127)
						)
						(arc
							(start -0.1524 0.127)
							(mid -0.137521 0.162921)
							(end -0.1016 0.1778)
						)
						(arc
							(start 0.1016 0.1778)
							(mid 0.137521 0.162921)
							(end 0.1524 0.127)
						)
					)
					(width 0)
					(fill yes)
				)
			)
		)
		(pad "2" smd custom
			(at 0 0.2794 90)
			(size 0.0762 0.0762)
			(layers "F.Cu" "F.Mask" "F.Paste")
			(net "PHY_SCC_B_TO_DRV_B_4_DN")
			(options
				(clearance outline)
				(anchor circle)
			)
			(primitives
				(gr_poly
					(pts
						(arc
							(start 0.1524 -0.127)
							(mid 0.137521 -0.162921)
							(end 0.1016 -0.1778)
						)
						(arc
							(start -0.1016 -0.1778)
							(mid -0.137521 -0.162921)
							(end -0.1524 -0.127)
						)
						(arc
							(start -0.1524 0.127)
							(mid -0.137521 0.162921)
							(end -0.1016 0.1778)
						)
						(arc
							(start 0.1016 0.1778)
							(mid 0.137521 0.162921)
							(end 0.1524 0.127)
						)
					)
					(width 0)
					(fill yes)
				)
			)
		)
	)
)
